# SCM (Grand Teton) — schematic netlist excerpt (pin names and nets, part order shuffled) for the footprints in the layout excerpt that follows; sources: Cadence DE-HDL packaged netlist, KiCad conversion of 12092022_DA0F0TMDCD0_F0T_Management_Board_D_brd_V3_OCP.brd

R80  Q_RES  220 1% CHIP  pkg 0402LF  page 50 : A = LED_D22_R ; B = P5V_AUX
R471  Q_RES  0 5% CHIP  pkg 0402LF  page 50 : A = REAR_AC_PWR_BTN ; B = AC_PWR_BTN_N

(kicad_pcb
	(version 20260206)
	(generator "pcbnew")
	(generator_version "10.0")
	(general
		(thickness 1.6)
		(legacy_teardrops no)
	)
	(paper "A4")
	(title_block
		(title "12092022_DA0F0TMDCD0_F0T_Management_Board_D_brd_V3_OCP.brd")
		(comment 1 "Grand Teton / footprints 456-457 of 1440")
	)
	(layers
		(0 "F.Cu" signal "TOP")
		(4 "In1.Cu" signal "GND")
		(6 "In2.Cu" signal "IN1")
		(8 "In3.Cu" signal "GND1")
		(10 "In4.Cu" signal "IN2")
		(12 "In5.Cu" signal "VCC")
		(14 "In6.Cu" signal "VCC1")
		(16 "In7.Cu" signal "IN3")
		(18 "In8.Cu" signal "GND2")
		(20 "In9.Cu" signal "IN4")
		(22 "In10.Cu" signal "GND3")
		(2 "B.Cu" signal "BOTTOM")
		(9 "F.Adhes" user "F.Adhesive")
		(11 "B.Adhes" user "B.Adhesive")
		(13 "F.Paste" user "Package Geometry/Pastemask Top")
		(15 "B.Paste" user "Package Geometry/Pastemask Bottom")
		(5 "F.SilkS" user "Ref Des/Silkscreen Top")
		(7 "B.SilkS" user "Ref Des/Silkscreen Bottom")
		(1 "F.Mask" user "Board Geometry/Soldermask Top")
		(3 "B.Mask" user "Board Geometry/Soldermask Bottom")
		(17 "Dwgs.User" user "User.Drawings")
		(19 "Cmts.User" user "User.Comments")
		(21 "Eco1.User" user "User.Eco1")
		(23 "Eco2.User" user "User.Eco2")
		(25 "Edge.Cuts" user "Board Geometry/Outline")
		(27 "Margin" user)
		(31 "F.CrtYd" user "Package Geometry/Place Bound Top")
		(29 "B.CrtYd" user "Package Geometry/Place Bound Bottom")
		(35 "F.Fab" user "Ref Des/Assembly Top")
		(33 "B.Fab" user "Ref Des/Assembly Bottom")
	)
	(footprint ""
		(layer "F.Cu")
		(at 60.198 -10.922 90)
		(property "Reference" "R80"
			(at 0 0 90)
			(layer "F.SilkS")
			(hide yes)
			(effects
				(font
					(size 1.27 1.27)
				)
			)
		)
		(property "Value" ""
			(at 0 0 90)
			(layer "F.Fab")
			(effects
				(font
					(size 1.27 1.27)
				)
			)
		)
		(duplicate_pad_numbers_are_jumpers no)
		(fp_line
			(start 0.7874 -0.4064)
			(end 0.7874 0.4064)
			(stroke
				(width 0.1524)
				(type default)
			)
			(layer "F.SilkS")
		)
		(fp_line
			(start -0.7874 -0.4064)
			(end 0.7874 -0.4064)
			(stroke
				(width 0.1524)
				(type default)
			)
			(layer "F.SilkS")
		)
		(fp_line
			(start 0.7874 0.4064)
			(end -0.7874 0.4064)
			(stroke
				(width 0.1524)
				(type default)
			)
			(layer "F.SilkS")
		)
		(fp_line
			(start -0.7874 0.4064)
			(end -0.7874 -0.4064)
			(stroke
				(width 0.1524)
				(type default)
			)
			(layer "F.SilkS")
		)
		(fp_line
			(start -0.12065 -0.305054)
			(end -0.12065 -0.2794)
			(stroke
				(width 0.1)
				(type default)
			)
			(layer "F.Fab")
		)
		(fp_line
			(start -0.67945 -0.305054)
			(end -0.12065 -0.305054)
			(stroke
				(width 0.1)
				(type default)
			)
			(layer "F.Fab")
		)
		(fp_line
			(start 0.67945 -0.3048)
			(end 0.67945 0.3048)
			(stroke
				(width 0.1)
				(type default)
			)
			(layer "F.Fab")
		)
		(fp_line
			(start 0.12065 -0.3048)
			(end 0.67945 -0.3048)
			(stroke
				(width 0.1)
				(type default)
			)
			(layer "F.Fab")
		)
		(fp_line
			(start 0.12065 -0.2794)
			(end 0.12065 -0.3048)
			(stroke
				(width 0.1)
				(type default)
			)
			(layer "F.Fab")
		)
		(fp_line
			(start -0.12065 -0.2794)
			(end 0.12065 -0.2794)
			(stroke
				(width 0.1)
				(type default)
			)
			(layer "F.Fab")
		)
		(fp_line
			(start 0.120396 0.2794)
			(end -0.12065 0.2794)
			(stroke
				(width 0.1)
				(type default)
			)
			(layer "F.Fab")
		)
		(fp_line
			(start -0.12065 0.2794)
			(end -0.12065 0.3048)
			(stroke
				(width 0.1)
				(type default)
			)
			(layer "F.Fab")
		)
		(fp_line
			(start 0.67945 0.3048)
			(end 0.120396 0.3048)
			(stroke
				(width 0.1)
				(type default)
			)
			(layer "F.Fab")
		)
		(fp_line
			(start 0.120396 0.3048)
			(end 0.120396 0.2794)
			(stroke
				(width 0.1)
				(type default)
			)
			(layer "F.Fab")
		)
		(fp_line
			(start -0.12065 0.3048)
			(end -0.67945 0.3048)
			(stroke
				(width 0.1)
				(type default)
			)
			(layer "F.Fab")
		)
		(fp_line
			(start -0.67945 0.3048)
			(end -0.67945 -0.305054)
			(stroke
				(width 0.1)
				(type default)
			)
			(layer "F.Fab")
		)
		(pad "1" smd circle
			(at -0.40005 0 90)
			(size 0 0)
			(layers "F.Cu" "F.Mask" "F.Paste")
			(net "LED_D22_R")
		)
		(pad "2" smd circle
			(at 0.40005 0 90)
			(size 0 0)
			(layers "F.Cu" "F.Mask" "F.Paste")
			(net "P5V_AUX")
		)
	)
	(footprint ""
		(layer "F.Cu")
		(at 72.644 -10.922 90)
		(property "Reference" "R471"
			(at 0 0 90)
			(layer "F.SilkS")
			(hide yes)
			(effects
				(font
					(size 1.27 1.27)
				)
			)
		)
		(property "Value" ""
			(at 0 0 90)
			(layer "F.Fab")
			(effects
				(font
					(size 1.27 1.27)
				)
			)
		)
		(duplicate_pad_numbers_are_jumpers no)
		(fp_line
			(start 0.7874 -0.4064)
			(end 0.7874 0.4064)
			(stroke
				(width 0.1524)
				(type default)
			)
			(layer "F.SilkS")
		)
		(fp_line
			(start -0.7874 -0.4064)
			(end 0.7874 -0.4064)
			(stroke
				(width 0.1524)
				(type default)
			)
			(layer "F.SilkS")
		)
		(fp_line
			(start 0.7874 0.4064)
			(end -0.7874 0.4064)
			(stroke
				(width 0.1524)
				(type default)
			)
			(layer "F.SilkS")
		)
		(fp_line
			(start -0.7874 0.4064)
			(end -0.7874 -0.4064)
			(stroke
				(width 0.1524)
				(type default)
			)
			(layer "F.SilkS")
		)
		(fp_line
			(start -0.12065 -0.305054)
			(end -0.12065 -0.2794)
			(stroke
				(width 0.1)
				(type default)
			)
			(layer "F.Fab")
		)
		(fp_line
			(start -0.67945 -0.305054)
			(end -0.12065 -0.305054)
			(stroke
				(width 0.1)
				(type default)
			)
			(layer "F.Fab")
		)
		(fp_line
			(start 0.67945 -0.3048)
			(end 0.67945 0.3048)
			(stroke
				(width 0.1)
				(type default)
			)
			(layer "F.Fab")
		)
		(fp_line
			(start 0.12065 -0.3048)
			(end 0.67945 -0.3048)
			(stroke
				(width 0.1)
				(type default)
			)
			(layer "F.Fab")
		)
		(fp_line
			(start 0.12065 -0.2794)
			(end 0.12065 -0.3048)
			(stroke
				(width 0.1)
				(type default)
			)
			(layer "F.Fab")
		)
		(fp_line
			(start -0.12065 -0.2794)
			(end 0.12065 -0.2794)
			(stroke
				(width 0.1)
				(type default)
			)
			(layer "F.Fab")
		)
		(fp_line
			(start 0.120396 0.2794)
			(end -0.12065 0.2794)
			(stroke
				(width 0.1)
				(type default)
			)
			(layer "F.Fab")
		)
		(fp_line
			(start -0.12065 0.2794)
			(end -0.12065 0.3048)
			(stroke
				(width 0.1)
				(type default)
			)
			(layer "F.Fab")
		)
		(fp_line
			(start 0.67945 0.3048)
			(end 0.120396 0.3048)
			(stroke
				(width 0.1)
				(type default)
			)
			(layer "F.Fab")
		)
		(fp_line
			(start 0.120396 0.3048)
			(end 0.120396 0.2794)
			(stroke
				(width 0.1)
				(type default)
			)
			(layer "F.Fab")
		)
		(fp_line
			(start -0.12065 0.3048)
			(end -0.67945 0.3048)
			(stroke
				(width 0.1)
				(type default)
			)
			(layer "F.Fab")
		)
		(fp_line
			(start -0.67945 0.3048)
			(end -0.67945 -0.305054)
			(stroke
				(width 0.1)
				(type default)
			)
			(layer "F.Fab")
		)
		(pad "1" smd circle
			(at -0.40005 0 90)
			(size 0 0)
			(layers "F.Cu" "F.Mask" "F.Paste")
			(net "REAR_AC_PWR_BTN")
		)
		(pad "2" smd circle
			(at 0.40005 0 90)
			(size 0 0)
			(layers "F.Cu" "F.Mask" "F.Paste")
			(net "AC_PWR_BTN_N")
		)
	)
)
